# S9S_MB_2U (Grand Teton) — schematic netlist excerpt (pin names and nets, part order shuffled) for the footprints in the layout excerpt that follows; sources: Cadence DE-HDL packaged netlist, KiCad conversion of 03242023_DA0F0TMBIJ0_F0T_Motherboard_J_brd_V01_OCP.brd

PC574_P1_1  Q_CAP  1UF 16V 10% X6S  pkg C0402  page 285 : A = PVCCIN_CPU1 ; B = GND

(kicad_pcb
	(version 20260206)
	(generator "pcbnew")
	(generator_version "10.0")
	(general
		(thickness 1.6)
		(legacy_teardrops no)
	)
	(paper "A4")
	(title_block
		(title "03242023_DA0F0TMBIJ0_F0T_Motherboard_J_brd_V01_OCP.brd")
		(comment 1 "Grand Teton / footprints 6000-6000 of 6105")
	)
	(layers
		(0 "F.Cu" signal "TOP")
		(4 "In1.Cu" signal "GND")
		(6 "In2.Cu" signal "IN1")
		(8 "In3.Cu" signal "GND1")
		(10 "In4.Cu" signal "IN2")
		(12 "In5.Cu" signal "GND2")
		(14 "In6.Cu" signal "IN3")
		(16 "In7.Cu" signal "GND3")
		(18 "In8.Cu" signal "VCC")
		(20 "In9.Cu" signal "VCC1")
		(22 "In10.Cu" signal "GND4")
		(24 "In11.Cu" signal "IN4")
		(26 "In12.Cu" signal "GND5")
		(28 "In13.Cu" signal "IN5")
		(30 "In14.Cu" signal "GND6")
		(32 "In15.Cu" signal "IN6")
		(34 "In16.Cu" signal "GND7")
		(2 "B.Cu" signal "BOTTOM")
		(9 "F.Adhes" user "F.Adhesive")
		(11 "B.Adhes" user "B.Adhesive")
		(13 "F.Paste" user "Package Geometry/Pastemask Top")
		(15 "B.Paste" user "Package Geometry/Pastemask Bottom")
		(5 "F.SilkS" user "Ref Des/Silkscreen Top")
		(7 "B.SilkS" user "Ref Des/Silkscreen Bottom")
		(1 "F.Mask" user "Board Geometry/Soldermask Top")
		(3 "B.Mask" user "Board Geometry/Soldermask Bottom")
		(17 "Dwgs.User" user "User.Drawings")
		(19 "Cmts.User" user "User.Comments")
		(21 "Eco1.User" user "User.Eco1")
		(23 "Eco2.User" user "User.Eco2")
		(25 "Edge.Cuts" user "Board Geometry/Outline")
		(27 "Margin" user)
		(31 "F.CrtYd" user "Package Geometry/Place Bound Top")
		(29 "B.CrtYd" user "Package Geometry/Place Bound Bottom")
		(35 "F.Fab" user "Ref Des/Assembly Top")
		(33 "B.Fab" user "Ref Des/Assembly Bottom")
	)
	(footprint ""
		(layer "B.Cu")
		(at 124.704602 -324.978776 -90)
		(property "Reference" "PC574_P1_1"
			(at 0 0 90)
			(layer "B.SilkS")
			(hide yes)
			(effects
				(font
					(size 1.27 1.27)
				)
				(justify mirror)
			)
		)
		(property "Value" ""
			(at 0 0 90)
			(layer "B.Fab")
			(effects
				(font
					(size 1.27 1.27)
				)
				(justify mirror)
			)
		)
		(duplicate_pad_numbers_are_jumpers no)
		(fp_line
			(start -0.7874 0.4064)
			(end 0.7874 0.4064)
			(stroke
				(width 0.1524)
				(type default)
			)
			(layer "B.SilkS")
		)
		(fp_line
			(start 0.7874 0.4064)
			(end 0.7874 -0.4064)
			(stroke
				(width 0.1524)
				(type default)
			)
			(layer "B.SilkS")
		)
		(fp_line
			(start -0.7874 -0.4064)
			(end -0.7874 0.4064)
			(stroke
				(width 0.1524)
				(type default)
			)
			(layer "B.SilkS")
		)
		(fp_line
			(start 0.7874 -0.4064)
			(end -0.7874 -0.4064)
			(stroke
				(width 0.1524)
				(type default)
			)
			(layer "B.SilkS")
		)
		(fp_line
			(start -0.67945 0.3048)
			(end -0.120396 0.3048)
			(stroke
				(width 0.1)
				(type default)
			)
			(layer "B.Fab")
		)
		(fp_line
			(start -0.120396 0.3048)
			(end -0.120396 0.2794)
			(stroke
				(width 0.1)
				(type default)
			)
			(layer "B.Fab")
		)
		(fp_line
			(start 0.12065 0.3048)
			(end 0.67945 0.3048)
			(stroke
				(width 0.1)
				(type default)
			)
			(layer "B.Fab")
		)
		(fp_line
			(start 0.67945 0.3048)
			(end 0.67945 -0.305054)
			(stroke
				(width 0.1)
				(type default)
			)
			(layer "B.Fab")
		)
		(fp_line
			(start -0.120396 0.2794)
			(end 0.12065 0.2794)
			(stroke
				(width 0.1)
				(type default)
			)
			(layer "B.Fab")
		)
		(fp_line
			(start 0.12065 0.2794)
			(end 0.12065 0.3048)
			(stroke
				(width 0.1)
				(type default)
			)
			(layer "B.Fab")
		)
		(fp_line
			(start -0.12065 -0.2794)
			(end -0.12065 -0.3048)
			(stroke
				(width 0.1)
				(type default)
			)
			(layer "B.Fab")
		)
		(fp_line
			(start 0.12065 -0.2794)
			(end -0.12065 -0.2794)
			(stroke
				(width 0.1)
				(type default)
			)
			(layer "B.Fab")
		)
		(fp_line
			(start -0.67945 -0.3048)
			(end -0.67945 0.3048)
			(stroke
				(width 0.1)
				(type default)
			)
			(layer "B.Fab")
		)
		(fp_line
			(start -0.12065 -0.3048)
			(end -0.67945 -0.3048)
			(stroke
				(width 0.1)
				(type default)
			)
			(layer "B.Fab")
		)
		(fp_line
			(start 0.12065 -0.305054)
			(end 0.12065 -0.2794)
			(stroke
				(width 0.1)
				(type default)
			)
			(layer "B.Fab")
		)
		(fp_line
			(start 0.67945 -0.305054)
			(end 0.12065 -0.305054)
			(stroke
				(width 0.1)
				(type default)
			)
			(layer "B.Fab")
		)
		(pad "1" smd circle
			(at 0.40005 0 90)
			(size 0 0)
			(layers "B.Cu" "B.Mask" "B.Paste")
			(net "PVCCIN_CPU1")
		)
		(pad "2" smd circle
			(at -0.40005 0 90)
			(size 0 0)
			(layers "B.Cu" "B.Mask" "B.Paste")
			(net "GND")
		)
	)
)
